(kicad_pcb
	(version 20260206)
	(generator "pcbnew")
	(generator_version "10.0")
	(general
		(thickness 1.6)
		(legacy_teardrops no)
	)
	(paper "A4")
	(title_block
		(title "04192023_DAF0TMB3IC0_F0TG_MB_C_brd_V02_OCP.brd")
		(comment 1 "Grand Teton / footprints 7352-7357 of 8354")
	)
	(layers
		(0 "F.Cu" signal "TOP")
		(4 "In1.Cu" signal "GND")
		(6 "In2.Cu" signal "IN1")
		(8 "In3.Cu" signal "GND1")
		(10 "In4.Cu" signal "IN2")
		(12 "In5.Cu" signal "GND2")
		(14 "In6.Cu" signal "IN3")
		(16 "In7.Cu" signal "GND3")
		(18 "In8.Cu" signal "VCC")
		(20 "In9.Cu" signal "VCC1")
		(22 "In10.Cu" signal "GND4")
		(24 "In11.Cu" signal "IN4")
		(26 "In12.Cu" signal "GND5")
		(28 "In13.Cu" signal "IN5")
		(30 "In14.Cu" signal "GND6")
		(32 "In15.Cu" signal "IN6")
		(34 "In16.Cu" signal "GND7")
		(2 "B.Cu" signal "BOTTOM")
		(9 "F.Adhes" user "F.Adhesive")
		(11 "B.Adhes" user "B.Adhesive")
		(13 "F.Paste" user "Package Geometry/Pastemask Top")
		(15 "B.Paste" user "Package Geometry/Pastemask Bottom")
		(5 "F.SilkS" user "Ref Des/Silkscreen Top")
		(7 "B.SilkS" user "Ref Des/Silkscreen Bottom")
		(1 "F.Mask" user "Board Geometry/Soldermask Top")
		(3 "B.Mask" user "Board Geometry/Soldermask Bottom")
		(17 "Dwgs.User" user "User.Drawings")
		(19 "Cmts.User" user "User.Comments")
		(21 "Eco1.User" user "User.Eco1")
		(23 "Eco2.User" user "User.Eco2")
		(25 "Edge.Cuts" user "Board Geometry/Outline")
		(27 "Margin" user)
		(31 "F.CrtYd" user "Package Geometry/Place Bound Top")
		(29 "B.CrtYd" user "Package Geometry/Place Bound Bottom")
		(35 "F.Fab" user "Ref Des/Assembly Top")
		(33 "B.Fab" user "Ref Des/Assembly Bottom")
	)
	(footprint ""
		(layer "B.Cu")
		(at 213.02091 -324.262242 180)
		(property "Reference" "L25"
			(at 0 0 0)
			(layer "B.SilkS")
			(hide yes)
			(effects
				(font
					(size 1.27 1.27)
				)
				(justify mirror)
			)
		)
		(property "Value" ""
			(at 0 0 0)
			(layer "B.Fab")
			(effects
				(font
					(size 1.27 1.27)
				)
				(justify mirror)
			)
		)
		(duplicate_pad_numbers_are_jumpers no)
		(fp_line
			(start 1.27 0.5842)
			(end 1.27 -0.5842)
			(stroke
				(width 0.1524)
				(type default)
			)
			(layer "B.SilkS")
		)
		(fp_line
			(start 1.27 -0.5588)
			(end 1.27 -0.5842)
			(stroke
				(width 0.1524)
				(type default)
			)
			(layer "B.SilkS")
		)
		(fp_line
			(start 1.27 -0.5842)
			(end -1.27 -0.5842)
			(stroke
				(width 0.1524)
				(type default)
			)
			(layer "B.SilkS")
		)
		(fp_line
			(start -1.27 0.5842)
			(end 1.27 0.5842)
			(stroke
				(width 0.1524)
				(type default)
			)
			(layer "B.SilkS")
		)
		(fp_line
			(start -1.27 0.5842)
			(end -1.27 -0.5842)
			(stroke
				(width 0.1524)
				(type default)
			)
			(layer "B.SilkS")
		)
		(fp_line
			(start 1.194308 0.406654)
			(end 1.194308 -0.406654)
			(stroke
				(width 0.1)
				(type default)
			)
			(layer "B.Fab")
		)
		(fp_line
			(start 1.194308 -0.406654)
			(end 0.9144 -0.406654)
			(stroke
				(width 0.1)
				(type default)
			)
			(layer "B.Fab")
		)
		(fp_line
			(start 0.9144 0.508)
			(end 0.9144 0.406654)
			(stroke
				(width 0.1)
				(type default)
			)
			(layer "B.Fab")
		)
		(fp_line
			(start 0.9144 0.406654)
			(end 1.194308 0.406654)
			(stroke
				(width 0.1)
				(type default)
			)
			(layer "B.Fab")
		)
		(fp_line
			(start 0.9144 -0.406654)
			(end 0.9144 -0.508)
			(stroke
				(width 0.1)
				(type default)
			)
			(layer "B.Fab")
		)
		(fp_line
			(start 0.9144 -0.508)
			(end -0.9144 -0.508)
			(stroke
				(width 0.1)
				(type default)
			)
			(layer "B.Fab")
		)
		(fp_line
			(start -0.9144 0.508)
			(end 0.9144 0.508)
			(stroke
				(width 0.1)
				(type default)
			)
			(layer "B.Fab")
		)
		(fp_line
			(start -0.9144 0.4064)
			(end -0.9144 0.508)
			(stroke
				(width 0.1)
				(type default)
			)
			(layer "B.Fab")
		)
		(fp_line
			(start -0.9144 -0.406654)
			(end -1.1938 -0.406654)
			(stroke
				(width 0.1)
				(type default)
			)
			(layer "B.Fab")
		)
		(fp_line
			(start -0.9144 -0.508)
			(end -0.9144 -0.406654)
			(stroke
				(width 0.1)
				(type default)
			)
			(layer "B.Fab")
		)
		(fp_line
			(start -1.1938 0.4064)
			(end -0.9144 0.4064)
			(stroke
				(width 0.1)
				(type default)
			)
			(layer "B.Fab")
		)
		(fp_line
			(start -1.1938 -0.406654)
			(end -1.1938 0.4064)
			(stroke
				(width 0.1)
				(type default)
			)
			(layer "B.Fab")
		)
		(pad "1" smd rect
			(at 0.7366 0 90)
			(size 0.7112 0.8128)
			(layers "B.Cu" "B.Mask" "B.Paste")
			(net "P3V3_AUX")
		)
		(pad "2" smd rect
			(at -0.7366 0 90)
			(size 0.7112 0.8128)
			(layers "B.Cu" "B.Mask" "B.Paste")
			(net "P3V3_ADC128_2_VCC")
		)
	)
	(footprint ""
		(layer "B.Cu")
		(at 383.818384 -396.393162 -90)
		(property "Reference" "C1014"
			(at 0 0 90)
			(layer "B.SilkS")
			(hide yes)
			(effects
				(font
					(size 1.27 1.27)
				)
				(justify mirror)
			)
		)
		(property "Value" ""
			(at 0 0 90)
			(layer "B.Fab")
			(effects
				(font
					(size 1.27 1.27)
				)
				(justify mirror)
			)
		)
		(duplicate_pad_numbers_are_jumpers no)
		(fp_line
			(start -0.299974 0.150114)
			(end 0.299974 0.150114)
			(stroke
				(width 0.1)
				(type default)
			)
			(layer "B.Fab")
		)
		(fp_line
			(start 0.299974 0.150114)
			(end 0.299974 -0.150114)
			(stroke
				(width 0.1)
				(type default)
			)
			(layer "B.Fab")
		)
		(fp_line
			(start -0.299974 -0.150114)
			(end -0.299974 0.150114)
			(stroke
				(width 0.1)
				(type default)
			)
			(layer "B.Fab")
		)
		(fp_line
			(start 0.299974 -0.150114)
			(end -0.299974 -0.150114)
			(stroke
				(width 0.1)
				(type default)
			)
			(layer "B.Fab")
		)
		(pad "1" smd rect
			(at 0.2667 0 90)
			(size 0.3048 0.381)
			(layers "B.Cu" "B.Mask" "B.Paste")
			(net "P0V9_CPU0_RT3_2A_2D")
		)
		(pad "2" smd rect
			(at -0.2667 0 90)
			(size 0.3048 0.381)
			(layers "B.Cu" "B.Mask" "B.Paste")
			(net "GND")
		)
	)
	(footprint ""
		(layer "B.Cu")
		(at 222.408242 -326.534272 180)
		(property "Reference" "U51"
			(at 0.015494 -3.693922 0)
			(unlocked yes)
			(layer "B.SilkS")
			(effects
				(font
					(size 0.7874 0.5842)
					(thickness 0.1524)
				)
				(justify left mirror)
			)
		)
		(property "Value" ""
			(at 0 0 0)
			(layer "B.Fab")
			(effects
				(font
					(size 1.27 1.27)
				)
				(justify mirror)
			)
		)
		(duplicate_pad_numbers_are_jumpers no)
		(fp_line
			(start 1.868932 2.549906)
			(end -1.868932 2.549906)
			(stroke
				(width 0.1524)
				(type default)
			)
			(layer "B.SilkS")
		)
		(fp_line
			(start 1.868932 -2.549906)
			(end 1.868932 2.549906)
			(stroke
				(width 0.1524)
				(type default)
			)
			(layer "B.SilkS")
		)
		(fp_line
			(start 1.025906 -2.549906)
			(end 1.868932 -2.549906)
			(stroke
				(width 0.1524)
				(type default)
			)
			(layer "B.SilkS")
		)
		(fp_line
			(start 0 -1.524)
			(end 1.025906 -2.549906)
			(stroke
				(width 0.1524)
				(type default)
			)
			(layer "B.SilkS")
		)
		(fp_line
			(start -1.025906 -2.549906)
			(end 0 -1.524)
			(stroke
				(width 0.1524)
				(type default)
			)
			(layer "B.SilkS")
		)
		(fp_line
			(start -1.868932 2.549906)
			(end -1.868932 -2.549906)
			(stroke
				(width 0.1524)
				(type default)
			)
			(layer "B.SilkS")
		)
		(fp_line
			(start -1.868932 -2.549906)
			(end -1.025906 -2.549906)
			(stroke
				(width 0.1524)
				(type default)
			)
			(layer "B.SilkS")
		)
		(fp_poly
			(pts
				(xy 4.948682 -3.169666) (xy 4.290822 -3.943858) (xy 3.84556 -2.898902)
			)
			(stroke
				(width 0)
				(type default)
			)
			(fill yes)
			(layer "B.SilkS")
		)
		(fp_line
			(start 2.249932 2.549906)
			(end -2.249932 2.549906)
			(stroke
				(width 0.1)
				(type default)
			)
			(layer "B.Fab")
		)
		(fp_line
			(start 2.249932 -2.549906)
			(end 2.249932 2.549906)
			(stroke
				(width 0.1)
				(type default)
			)
			(layer "B.Fab")
		)
		(fp_line
			(start -2.249932 2.549906)
			(end -2.249932 -2.549906)
			(stroke
				(width 0.1)
				(type default)
			)
			(layer "B.Fab")
		)
		(fp_line
			(start -2.249932 -2.549906)
			(end 2.249932 -2.549906)
			(stroke
				(width 0.1)
				(type default)
			)
			(layer "B.Fab")
		)
		(fp_poly
			(pts
				(xy 4.7752 -1.787398) (xy 4.7752 -2.803398) (xy 3.7592 -2.295398)
			)
			(stroke
				(width 0)
				(type default)
			)
			(fill yes)
			(layer "B.Fab")
		)
		(pad "1" smd rect
			(at 2.800096 -2.275078 90)
			(size 0.3556 1.6002)
			(layers "B.Cu" "B.Mask" "B.Paste")
			(net "ADC128_2_VREF")
		)
		(pad "2" smd rect
			(at 2.800096 -1.625092 90)
			(size 0.3556 1.6002)
			(layers "B.Cu" "B.Mask" "B.Paste")
			(net "SMB_SEN_TIC_2_3V3AUX_SDA")
		)
		(pad "3" smd rect
			(at 2.800096 -0.975106 90)
			(size 0.3556 1.6002)
			(layers "B.Cu" "B.Mask" "B.Paste")
			(net "SMB_SEN_TIC_2_3V3AUX_SCL")
		)
		(pad "4" smd rect
			(at 2.800096 -0.32512 90)
			(size 0.3556 1.6002)
			(layers "B.Cu" "B.Mask" "B.Paste")
			(net "GND")
		)
		(pad "5" smd rect
			(at 2.800096 0.32512 90)
			(size 0.3556 1.6002)
			(layers "B.Cu" "B.Mask" "B.Paste")
			(net "P3V3_ADC128_2_VCC")
		)
		(pad "6" smd rect
			(at 2.800096 0.975106 90)
			(size 0.3556 1.6002)
			(layers "B.Cu" "B.Mask" "B.Paste")
			(net "TP_ADC128_2_INT")
		)
		(pad "7" smd rect
			(at 2.800096 1.625092 90)
			(size 0.3556 1.6002)
			(layers "B.Cu" "B.Mask" "B.Paste")
			(net "ADC128_2_A0")
		)
		(pad "8" smd rect
			(at 2.800096 2.275078 90)
			(size 0.3556 1.6002)
			(layers "B.Cu" "B.Mask" "B.Paste")
			(net "ADC128_2_A1")
		)
		(pad "9" smd rect
			(at -2.800096 2.275078 90)
			(size 0.3556 1.6002)
			(layers "B.Cu" "B.Mask" "B.Paste")
			(net "PVDD18_S5_P1_ADC_TIC")
		)
		(pad "10" smd rect
			(at -2.800096 1.625092 90)
			(size 0.3556 1.6002)
			(layers "B.Cu" "B.Mask" "B.Paste")
			(net "PVDD18_S5_P0_ADC_TIC")
		)
		(pad "11" smd rect
			(at -2.800096 0.975106 90)
			(size 0.3556 1.6002)
			(layers "B.Cu" "B.Mask" "B.Paste")
			(net "PVDD_33_S5_ADC_TIC")
		)
		(pad "12" smd rect
			(at -2.800096 0.32512 90)
			(size 0.3556 1.6002)
			(layers "B.Cu" "B.Mask" "B.Paste")
			(net "P1V8_CPU1_RT_1D_ADC_TIC")
		)
		(pad "13" smd rect
			(at -2.800096 -0.32512 90)
			(size 0.3556 1.6002)
			(layers "B.Cu" "B.Mask" "B.Paste")
			(net "P1V8_CPU0_RT_1D_ADC_TIC")
		)
		(pad "14" smd rect
			(at -2.800096 -0.975106 90)
			(size 0.3556 1.6002)
			(layers "B.Cu" "B.Mask" "B.Paste")
			(net "P1V2_AUX_ADC_TIC")
		)
		(pad "15" smd rect
			(at -2.800096 -1.625092 90)
			(size 0.3556 1.6002)
			(layers "B.Cu" "B.Mask" "B.Paste")
			(net "P1V8_AUX_ADC_TIC")
		)
		(pad "16" smd rect
			(at -2.800096 -2.275078 90)
			(size 0.3556 1.6002)
			(layers "B.Cu" "B.Mask" "B.Paste")
			(net "P5V_AUX_ADC_TIC")
		)
	)
	(footprint ""
		(layer "B.Cu")
		(at 231.029002 -329.365102)
		(property "Reference" "R1256"
			(at 0 0 0)
			(layer "B.SilkS")
			(hide yes)
			(effects
				(font
					(size 1.27 1.27)
				)
				(justify mirror)
			)
		)
		(property "Value" ""
			(at 0 0 0)
			(layer "B.Fab")
			(effects
				(font
					(size 1.27 1.27)
				)
				(justify mirror)
			)
		)
		(duplicate_pad_numbers_are_jumpers no)
		(fp_line
			(start -0.7874 -0.4064)
			(end -0.7874 0.4064)
			(stroke
				(width 0.1524)
				(type default)
			)
			(layer "B.SilkS")
		)
		(fp_line
			(start -0.7874 0.4064)
			(end 0.7874 0.4064)
			(stroke
				(width 0.1524)
				(type default)
			)
			(layer "B.SilkS")
		)
		(fp_line
			(start 0.7874 -0.4064)
			(end -0.7874 -0.4064)
			(stroke
				(width 0.1524)
				(type default)
			)
			(layer "B.SilkS")
		)
		(fp_line
			(start 0.7874 0.4064)
			(end 0.7874 -0.4064)
			(stroke
				(width 0.1524)
				(type default)
			)
			(layer "B.SilkS")
		)
		(fp_line
			(start -0.67945 -0.3048)
			(end -0.67945 0.3048)
			(stroke
				(width 0.1)
				(type default)
			)
			(layer "B.Fab")
		)
		(fp_line
			(start -0.67945 0.3048)
			(end -0.120396 0.3048)
			(stroke
				(width 0.1)
				(type default)
			)
			(layer "B.Fab")
		)
		(fp_line
			(start -0.12065 -0.3048)
			(end -0.67945 -0.3048)
			(stroke
				(width 0.1)
				(type default)
			)
			(layer "B.Fab")
		)
		(fp_line
			(start -0.12065 -0.2794)
			(end -0.12065 -0.3048)
			(stroke
				(width 0.1)
				(type default)
			)
			(layer "B.Fab")
		)
		(fp_line
			(start -0.120396 0.2794)
			(end 0.12065 0.2794)
			(stroke
				(width 0.1)
				(type default)
			)
			(layer "B.Fab")
		)
		(fp_line
			(start -0.120396 0.3048)
			(end -0.120396 0.2794)
			(stroke
				(width 0.1)
				(type default)
			)
			(layer "B.Fab")
		)
		(fp_line
			(start 0.12065 -0.305054)
			(end 0.12065 -0.2794)
			(stroke
				(width 0.1)
				(type default)
			)
			(layer "B.Fab")
		)
		(fp_line
			(start 0.12065 -0.2794)
			(end -0.12065 -0.2794)
			(stroke
				(width 0.1)
				(type default)
			)
			(layer "B.Fab")
		)
		(fp_line
			(start 0.12065 0.2794)
			(end 0.12065 0.3048)
			(stroke
				(width 0.1)
				(type default)
			)
			(layer "B.Fab")
		)
		(fp_line
			(start 0.12065 0.3048)
			(end 0.67945 0.3048)
			(stroke
				(width 0.1)
				(type default)
			)
			(layer "B.Fab")
		)
		(fp_line
			(start 0.67945 -0.305054)
			(end 0.12065 -0.305054)
			(stroke
				(width 0.1)
				(type default)
			)
			(layer "B.Fab")
		)
		(fp_line
			(start 0.67945 0.3048)
			(end 0.67945 -0.305054)
			(stroke
				(width 0.1)
				(type default)
			)
			(layer "B.Fab")
		)
		(pad "1" smd rect
			(at 0.40005 0)
			(size 0.4572 0.508)
			(layers "B.Cu" "B.Mask" "B.Paste")
			(net "PVDD18_S5_P1_ADC")
		)
		(pad "2" smd rect
			(at -0.40005 0)
			(size 0.4572 0.508)
			(layers "B.Cu" "B.Mask" "B.Paste")
			(net "PVDD18_S5_P1_ADC_TIC")
		)
	)
	(footprint ""
		(layer "B.Cu")
		(at 50.718974 -418.707316 180)
		(property "Reference" "R5234"
			(at 0 0 0)
			(layer "B.SilkS")
			(hide yes)
			(effects
				(font
					(size 1.27 1.27)
				)
				(justify mirror)
			)
		)
		(property "Value" ""
			(at 0 0 0)
			(layer "B.Fab")
			(effects
				(font
					(size 1.27 1.27)
				)
				(justify mirror)
			)
		)
		(duplicate_pad_numbers_are_jumpers no)
		(fp_line
			(start 0.7874 0.4064)
			(end 0.7874 -0.4064)
			(stroke
				(width 0.1524)
				(type default)
			)
			(layer "B.SilkS")
		)
		(fp_line
			(start 0.7874 -0.4064)
			(end -0.7874 -0.4064)
			(stroke
				(width 0.1524)
				(type default)
			)
			(layer "B.SilkS")
		)
		(fp_line
			(start -0.7874 0.4064)
			(end 0.7874 0.4064)
			(stroke
				(width 0.1524)
				(type default)
			)
			(layer "B.SilkS")
		)
		(fp_line
			(start -0.7874 -0.4064)
			(end -0.7874 0.4064)
			(stroke
				(width 0.1524)
				(type default)
			)
			(layer "B.SilkS")
		)
		(fp_line
			(start 0.67945 0.3048)
			(end 0.67945 -0.305054)
			(stroke
				(width 0.1)
				(type default)
			)
			(layer "B.Fab")
		)
		(fp_line
			(start 0.67945 -0.305054)
			(end 0.12065 -0.305054)
			(stroke
				(width 0.1)
				(type default)
			)
			(layer "B.Fab")
		)
		(fp_line
			(start 0.12065 0.3048)
			(end 0.67945 0.3048)
			(stroke
				(width 0.1)
				(type default)
			)
			(layer "B.Fab")
		)
		(fp_line
			(start 0.12065 0.2794)
			(end 0.12065 0.3048)
			(stroke
				(width 0.1)
				(type default)
			)
			(layer "B.Fab")
		)
		(fp_line
			(start 0.12065 -0.2794)
			(end -0.12065 -0.2794)
			(stroke
				(width 0.1)
				(type default)
			)
			(layer "B.Fab")
		)
		(fp_line
			(start 0.12065 -0.305054)
			(end 0.12065 -0.2794)
			(stroke
				(width 0.1)
				(type default)
			)
			(layer "B.Fab")
		)
		(fp_line
			(start -0.120396 0.3048)
			(end -0.120396 0.2794)
			(stroke
				(width 0.1)
				(type default)
			)
			(layer "B.Fab")
		)
		(fp_line
			(start -0.120396 0.2794)
			(end 0.12065 0.2794)
			(stroke
				(width 0.1)
				(type default)
			)
			(layer "B.Fab")
		)
		(fp_line
			(start -0.12065 -0.2794)
			(end -0.12065 -0.3048)
			(stroke
				(width 0.1)
				(type default)
			)
			(layer "B.Fab")
		)
		(fp_line
			(start -0.12065 -0.3048)
			(end -0.67945 -0.3048)
			(stroke
				(width 0.1)
				(type default)
			)
			(layer "B.Fab")
		)
		(fp_line
			(start -0.67945 0.3048)
			(end -0.120396 0.3048)
			(stroke
				(width 0.1)
				(type default)
			)
			(layer "B.Fab")
		)
		(fp_line
			(start -0.67945 -0.3048)
			(end -0.67945 0.3048)
			(stroke
				(width 0.1)
				(type default)
			)
			(layer "B.Fab")
		)
		(pad "1" smd circle
			(at 0.40005 0)
			(size 0 0)
			(layers "B.Cu" "B.Mask" "B.Paste")
			(net "USB2_HUB_BUF_SWB_R_DP")
		)
		(pad "2" smd circle
			(at -0.40005 0)
			(size 0 0)
			(layers "B.Cu" "B.Mask" "B.Paste")
			(net "USB2_HUB_BUF_SWB_DP")
		)
	)
	(footprint ""
		(layer "B.Cu")
		(at 357.515922 -256.012188 -90)
		(property "Reference" "C2546"
			(at 0 0 90)
			(layer "B.SilkS")
			(hide yes)
			(effects
				(font
					(size 1.27 1.27)
				)
				(justify mirror)
			)
		)
		(property "Value" ""
			(at 0 0 90)
			(layer "B.Fab")
			(effects
				(font
					(size 1.27 1.27)
				)
				(justify mirror)
			)
		)
		(duplicate_pad_numbers_are_jumpers no)
		(fp_line
			(start -0.7874 0.4064)
			(end 0.7874 0.4064)
			(stroke
				(width 0.1524)
				(type default)
			)
			(layer "B.SilkS")
		)
		(fp_line
			(start 0.7874 0.4064)
			(end 0.7874 -0.4064)
			(stroke
				(width 0.1524)
				(type default)
			)
			(layer "B.SilkS")
		)
		(fp_line
			(start -0.7874 -0.4064)
			(end -0.7874 0.4064)
			(stroke
				(width 0.1524)
				(type default)
			)
			(layer "B.SilkS")
		)
		(fp_line
			(start 0.7874 -0.4064)
			(end -0.7874 -0.4064)
			(stroke
				(width 0.1524)
				(type default)
			)
			(layer "B.SilkS")
		)
		(fp_line
			(start -0.67945 0.3048)
			(end -0.120396 0.3048)
			(stroke
				(width 0.1)
				(type default)
			)
			(layer "B.Fab")
		)
		(fp_line
			(start -0.120396 0.3048)
			(end -0.120396 0.2794)
			(stroke
				(width 0.1)
				(type default)
			)
			(layer "B.Fab")
		)
		(fp_line
			(start 0.12065 0.3048)
			(end 0.67945 0.3048)
			(stroke
				(width 0.1)
				(type default)
			)
			(layer "B.Fab")
		)
		(fp_line
			(start 0.67945 0.3048)
			(end 0.67945 -0.305054)
			(stroke
				(width 0.1)
				(type default)
			)
			(layer "B.Fab")
		)
		(fp_line
			(start -0.120396 0.2794)
			(end 0.12065 0.2794)
			(stroke
				(width 0.1)
				(type default)
			)
			(layer "B.Fab")
		)
		(fp_line
			(start 0.12065 0.2794)
			(end 0.12065 0.3048)
			(stroke
				(width 0.1)
				(type default)
			)
			(layer "B.Fab")
		)
		(fp_line
			(start -0.12065 -0.2794)
			(end -0.12065 -0.3048)
			(stroke
				(width 0.1)
				(type default)
			)
			(layer "B.Fab")
		)
		(fp_line
			(start 0.12065 -0.2794)
			(end -0.12065 -0.2794)
			(stroke
				(width 0.1)
				(type default)
			)
			(layer "B.Fab")
		)
		(fp_line
			(start -0.67945 -0.3048)
			(end -0.67945 0.3048)
			(stroke
				(width 0.1)
				(type default)
			)
			(layer "B.Fab")
		)
		(fp_line
			(start -0.12065 -0.3048)
			(end -0.67945 -0.3048)
			(stroke
				(width 0.1)
				(type default)
			)
			(layer "B.Fab")
		)
		(fp_line
			(start 0.12065 -0.305054)
			(end 0.12065 -0.2794)
			(stroke
				(width 0.1)
				(type default)
			)
			(layer "B.Fab")
		)
		(fp_line
			(start 0.67945 -0.305054)
			(end 0.12065 -0.305054)
			(stroke
				(width 0.1)
				(type default)
			)
			(layer "B.Fab")
		)
		(pad "1" smd circle
			(at 0.40005 0 90)
			(size 0 0)
			(layers "B.Cu" "B.Mask" "B.Paste")
			(net "PVDDCR_SOC_P0")
		)
		(pad "2" smd circle
			(at -0.40005 0 90)
			(size 0 0)
			(layers "B.Cu" "B.Mask" "B.Paste")
			(net "GND")
		)
	)
)
